FILE_TYPE = CONNECTIVITY;
{Allegro Design Entry HDL 17.4-2019 S026 (4007227) 1/17/2022}
"PAGE_NUMBER" = 138;
0"NC";
1"GND\g";
2"GND\g";
3"GND\g";
4"GND\g";
5"GND\g";
6"GND\g";
7"GND\g";
8"GND\g";
9"SMB_APML_CPU0_MUX2_SDA";
10"FM_APML_MUX2_OE_N";
11"FM_APML_MUX2_SEL";
12"SMB_CPU0_CPU1_APML_MUX2_SDA";
13"SMB_CPU0_CPU1_APML_MUX2_SCL";
14"SMB_CPU0_CPU1_APML_SDA_R2";
15"I3C_MUX_CPU0_VIO";
16"SMB_CPU0_CPU1_APML_MUX1_SDA";
17"SMB_CPU0_CPU1_APML_MUX1_SCL";
18"SMB_CPU0_CPU1_APML_SDA_R2";
19"SMB_APML_CPU0_R_SCL";
20"SMB_CPU0_CPU1_APML_SCL_R2";
21"SMB_CPU0_SEC_R_SDA";
22"SMB_CPU0_SEC_R_SCL";
23"SMB_CPU0_CPU1_SEC_SCL_R2";
24"SMB_CPU0_CPU1_SEC_SDA_R2";
25"SMB_APML_CPU1_SDA";
26"SMB_APML_CPU1_SCL";
27"SMB_APML_CPU0_SDA";
28"SMB_APML_CPU0_SCL";
29"SMB_CPU1_SEC_SCL";
30"SMB_CPU1_SEC_SDA";
31"SMB_CPU1_SEC_R_SCL";
32"SMB_CPU1_SEC_R_SDA";
33"FM_SEC_MUX_OE_N";
34"SMB_CPU0_SEC_SCL";
35"SMB_CPU0_SEC_SDA";
36"FM_SEC_MUX_SEL";
37"SMB_CPU1_SEC_SCL";
38"SMB_CPU1_SEC_SDA";
39"SMB_CPU0_SEC_SCL";
40"SMB_CPU0_SEC_SDA";
41"SMB_APML_CPU0_SCL";
42"SMB_APML_CPU1_SDA";
43"SMB_APML_CPU1_SCL";
44"SMB_APML_CPU0_SDA";
45"SMB_APML_CPU1_R_SCL";
46"SMB_APML_CPU1_R_SDA";
47"SMB_APML_CPU0_R_SDA";
48"SMB_CPU0_CPU1_APML_SCL_R2";
49"SMB_APML_CPU0_SCL";
50"SMB_APML_CPU0_MUX2_SCL";
51"SMB_APML_CPU0_SDA";
52"SMB_APML_CPU1_SCL";
53"SMB_APML_CPU1_MUX2_SCL";
54"SMB_APML_CPU1_SDA";
55"SMB_APML_CPU1_MUX2_SDA";
56"P3V3_AUX\g";
57"P3V3_AUX\g";
58"PVDD18_S5_P0\g";
59"PVDD11_S3_P1\g";
60"PVDD11_S3_P0\g";
61"PVDD18_S5_P0\g";
62"PVDD18_S5_P1\g";
%"Q_RES"
"1","(3025,5500)","0","pure_quanta","I100";
;
LOCATION"R326"
$SEC"1"
CDS_SEC"1"
VALUE"0"
PACK_TYPE"0402LF"
MATERIAL"CHIP"
TOLERANCE"5%"
WATTAGE"1/16W"
CDS_LIB"pure_quanta"
PART_NUMBER"CS00002JB13";
"B"
$PN"2"12;
"A"
$PN"1"14;
%"Q_RES"
"1","(-575,3875)","0","pure_quanta","I109";
;
LOCATION"R323"
$SEC"1"
CDS_SEC"1"
VALUE"0"
MATERIAL"EMPTY"
PACK_TYPE"0402LF"
TOLERANCE"5%"
WATTAGE"1/16W"
CDS_LIB"pure_quanta"
PART_NUMBER"CS00002JB13";
"B"
$PN"2"16;
"A"
$PN"1"18;
%"Q_RES"
"1","(-575,3825)","0","pure_quanta","I110";
;
LOCATION"R324"
$SEC"1"
CDS_SEC"1"
VALUE"0"
MATERIAL"EMPTY"
WATTAGE"1/16W"
TOLERANCE"5%"
PACK_TYPE"0402LF"
CDS_LIB"pure_quanta"
PART_NUMBER"CS00002JB13";
"B"
$PN"2"17;
"A"
$PN"1"20;
%"IML3112Y2B000NCG8"
"1","(1675,3925)","0","pure_quanta","I111";
;
LOCATION"U213"
SEC"1"
MATERIAL"EMPTY"
VALUE"IML3112-Y2B000NCG8"
PART_TYPE"SMLF"
CDS_LIB"pure_quanta"
NEEDS_NO_SIZE"TRUE"
CDS_LMAN_SYM_OUTLINE"-275,250,275,-250"
SEC_TYPE""
PART_NUMBER"AL003112004";
"TH_GND"
$PN"9"2;
"LSDA_1||HSA"
$PN"8"46;
"HSCL"
$PN"3"17;
"LSCL_0"
$PN"4"19;
"LSDA_0"
$PN"1"47;
"VIO"
$PN"7"15;
"LSCL_1"
$PN"6"45;
"VDD"
$PN"5"58;
"HSDA"
$PN"2"16;
%"Q_CAP"
"1","(700,4350)","2","pure_quanta","I112";
;
LOCATION"C24"
$SEC"1"
CDS_SEC"1"
PACK_TYPE"C0402"
MATERIAL"EMPTY"
VALUE"10UF"
TOLERANCE"20%"
VOLTAGE"6.3V"
CDS_LIB"pure_quanta"
PART_NUMBER"CH6101MEB01";
"B"
$PN"2"5;
"A"
$PN"1"58;
%"Q_CAP"
"1","(175,4350)","2","pure_quanta","I113";
;
LOCATION"C9"
$SEC"1"
CDS_SEC"1"
VOLTAGE"25V"
PACK_TYPE"C0402"
MATERIAL"EMPTY"
TOLERANCE"10%"
VALUE"1UF"
CDS_LIB"pure_quanta"
PART_NUMBER"CH5104KEB02";
"B"
$PN"2"4;
"A"
$PN"1"15;
%"PI3CSW12ZUAEX"
"1","(4600,5450)","2","pure_quanta","I114";
;
LOCATION"U4"
SEC"1"
VALUE"PI3CSW12ZUAEX"
PART_TYPE"SMLF"
MATERIAL"IC"
SEC_TYPE""
CDS_LMAN_SYM_OUTLINE"-150,200,150,-200"
NEEDS_NO_SIZE"TRUE"
CDS_LIB"pure_quanta"
PART_NUMBER"AL3CSW12000";
"D+"
$PN"8"13;
"GND"
$PN"5"7;
"1D-"
$PN"2"9;
"VDD"
$PN"10"56;
"S"
$PN"9"11;
"OE# \B"
$PN"6"10;
"D-"
$PN"7"12;
"2D-"
$PN"4"55;
"2D+"
$PN"3"53;
"1D+"
$PN"1"50;
%"P1V0"
"1","(1150,2650)","0","pure_quanta_power","I13";
;
HDL_POWER"P3V3_AUX"
CDS_LIB"pure_quanta_power";
"A"57;
%"Q_RES"
"1","(1650,2800)","0","pure_quanta","I14";
;
LOCATION"R145"
$SEC"1"
CDS_SEC"1"
MATERIAL"EMPTY"
VALUE"0"
CDS_LIB"pure_quanta"
WATTAGE"1/16W"
TOLERANCE"5%"
PACK_TYPE"0402LF"
PART_NUMBER"CS00002JB13";
"B"
$PN"2"22;
"A"
$PN"1"23;
%"Q_RES"
"1","(1650,2875)","0","pure_quanta","I15";
;
LOCATION"R144"
$SEC"1"
CDS_SEC"1"
MATERIAL"EMPTY"
VALUE"0"
CDS_LIB"pure_quanta"
WATTAGE"1/16W"
TOLERANCE"5%"
PACK_TYPE"0402LF"
PART_NUMBER"CS00002JB13";
"B"
$PN"2"21;
"A"
$PN"1"24;
%"Q_RES"
"1","(1700,3150)","0","pure_quanta","I16";
;
LOCATION"R147"
$SEC"1"
CDS_SEC"1"
MATERIAL"EMPTY"
VALUE"0"
CDS_LIB"pure_quanta"
WATTAGE"1/16W"
TOLERANCE"5%"
PACK_TYPE"0402LF"
PART_NUMBER"CS00002JB13";
"B"
$PN"2"46;
"A"
$PN"1"16;
%"Q_RES"
"1","(1700,3225)","0","pure_quanta","I17";
;
LOCATION"R146"
$SEC"1"
CDS_SEC"1"
VALUE"0"
MATERIAL"EMPTY"
CDS_LIB"pure_quanta"
WATTAGE"1/16W"
TOLERANCE"5%"
PACK_TYPE"0402LF"
PART_NUMBER"CS00002JB13";
"B"
$PN"2"45;
"A"
$PN"1"17;
%"UNIVERSAL_GND"
"1","(1225,1600)","0","pure_quanta_power","I18";
;
CDS_LIB"pure_quanta_power"
HDL_POWER"GND";
"A"1;
%"UNIVERSAL_GND"
"1","(2125,3575)","0","pure_quanta_power","I21";
;
CDS_LIB"pure_quanta_power"
HDL_POWER"GND";
"A"2;
%"Q_RES"
"1","(3175,1775)","0","pure_quanta","I22";
;
LOCATION"R1162"
$SEC"1"
CDS_SEC"1"
VALUE"0"
PACK_TYPE"0402LF"
TOLERANCE"5%"
MATERIAL"CHIP"
WATTAGE"1/16W"
CDS_LIB"pure_quanta"
PART_NUMBER"CS00002JB13";
"B"
$PN"2"30;
"A"
$PN"1"32;
%"Q_RES"
"1","(3175,1825)","0","pure_quanta","I23";
;
LOCATION"R1161"
$SEC"1"
CDS_SEC"1"
VALUE"0"
CDS_LIB"pure_quanta"
WATTAGE"1/16W"
MATERIAL"CHIP"
TOLERANCE"5%"
PACK_TYPE"0402LF"
PART_NUMBER"CS00002JB13";
"B"
$PN"2"29;
"A"
$PN"1"31;
%"UNIVERSAL_GND"
"1","(2800,3350)","0","pure_quanta_power","I26";
;
CDS_LIB"pure_quanta_power"
HDL_POWER"GND";
"A"3;
%"Q_RES"
"2","(2800,3600)","0","pure_quanta","I27";
;
LOCATION"R5004"
$SEC"1"
CDS_SEC"1"
MATERIAL"CHIP"
PACK_TYPE"0402LF"
TOLERANCE"1%"
VALUE"10K"
WATTAGE"1/16W"
CDS_LIB"pure_quanta"
PART_NUMBER"CS31002FB08";
"A"
$PN"1"46;
"B"
$PN"2"3;
%"UNIVERSAL_GND"
"1","(175,4150)","0","pure_quanta_power","I28";
;
CDS_LIB"pure_quanta_power"
HDL_POWER"GND";
"A"4;
%"Q_RES"
"1","(425,4525)","0","pure_quanta","I30";
;
LOCATION"R139"
$SEC"1"
CDS_SEC"1"
VALUE"0"
MATERIAL"EMPTY"
CDS_LIB"pure_quanta"
WATTAGE"1/16W"
TOLERANCE"5%"
PACK_TYPE"0402LF"
PART_NUMBER"CS00002JB13";
"B"
$PN"2"58;
"A"
$PN"1"15;
%"UNIVERSAL_GND"
"1","(700,4150)","0","pure_quanta_power","I31";
;
CDS_LIB"pure_quanta_power"
HDL_POWER"GND";
"A"5;
%"P1V0"
"1","(875,4700)","0","pure_quanta_power","I33";
;
HDL_POWER"PVDD18_S5_P0"
CDS_LIB"pure_quanta_power";
"A"58;
%"Q_RES"
"1","(1650,4925)","0","pure_quanta","I34";
;
LOCATION"R143"
$SEC"1"
CDS_SEC"1"
MATERIAL"EMPTY"
VALUE"0"
CDS_LIB"pure_quanta"
WATTAGE"1/16W"
TOLERANCE"5%"
PACK_TYPE"0402LF"
PART_NUMBER"CS00002JB13";
"B"
$PN"2"47;
"A"
$PN"1"16;
%"Q_RES"
"1","(1650,5000)","0","pure_quanta","I35";
;
LOCATION"R142"
$SEC"1"
CDS_SEC"1"
MATERIAL"EMPTY"
VALUE"0"
CDS_LIB"pure_quanta"
WATTAGE"1/16W"
TOLERANCE"5%"
PACK_TYPE"0402LF"
PART_NUMBER"CS00002JB13";
"B"
$PN"2"19;
"A"
$PN"1"17;
%"Q_RES"
"1","(3150,3975)","0","pure_quanta","I38";
;
LOCATION"R1156"
$SEC"1"
CDS_SEC"1"
MATERIAL"EMPTY"
VALUE"33"
CDS_LIB"pure_quanta"
WATTAGE"1/16W"
TOLERANCE"5%"
PACK_TYPE"0402LF"
PART_NUMBER"CS03302JB10";
"B"
$PN"2"41;
"A"
$PN"1"19;
%"Q_RES"
"1","(3150,4025)","0","pure_quanta","I39";
;
LOCATION"R1155"
$SEC"1"
CDS_SEC"1"
MATERIAL"EMPTY"
VALUE"33"
PACK_TYPE"0402LF"
TOLERANCE"5%"
WATTAGE"1/16W"
CDS_LIB"pure_quanta"
PART_NUMBER"CS03302JB10";
"B"
$PN"2"44;
"A"
$PN"1"47;
%"Q_RES"
"1","(1725,1025)","0","pure_quanta","I5";
;
LOCATION"R358"
$SEC"1"
CDS_SEC"1"
VALUE"0"
MATERIAL"EMPTY"
CDS_LIB"pure_quanta"
WATTAGE"1/16W"
TOLERANCE"5%"
PACK_TYPE"0402LF"
PART_NUMBER"CS00002JB13";
"B"
$PN"2"31;
"A"
$PN"1"23;
%"Q_RES"
"2","(5900,2725)","0","pure_quanta","I52";
;
LOCATION"R359"
$SEC"1"
CDS_SEC"1"
VALUE"1K"
TOLERANCE"1%"
WATTAGE"1/16W"
MATERIAL"CHIP"
PACK_TYPE"0402LF"
CDS_LIB"pure_quanta"
PART_NUMBER"CS21002FB06";
"A"
$PN"1"59;
"B"
$PN"2"25;
%"Q_RES"
"2","(6225,2725)","0","pure_quanta","I53";
;
LOCATION"R362"
$SEC"1"
CDS_SEC"1"
WATTAGE"1/16W"
MATERIAL"CHIP"
PACK_TYPE"0402LF"
TOLERANCE"1%"
VALUE"1K"
CDS_LIB"pure_quanta"
PART_NUMBER"CS21002FB06";
"A"
$PN"1"59;
"B"
$PN"2"26;
%"Q_RES"
"2","(6525,2725)","0","pure_quanta","I54";
;
LOCATION"R366"
$SEC"1"
CDS_SEC"1"
MATERIAL"CHIP"
PACK_TYPE"0402LF"
WATTAGE"1/16W"
TOLERANCE"1%"
VALUE"1K"
CDS_LIB"pure_quanta"
PART_NUMBER"CS21002FB06";
"A"
$PN"1"62;
"B"
$PN"2"37;
%"Q_RES"
"2","(5925,3650)","0","pure_quanta","I55";
;
LOCATION"R360"
$SEC"1"
CDS_SEC"1"
WATTAGE"1/16W"
MATERIAL"CHIP"
PACK_TYPE"0402LF"
TOLERANCE"1%"
VALUE"1K"
CDS_LIB"pure_quanta"
PART_NUMBER"CS21002FB06";
"A"
$PN"1"60;
"B"
$PN"2"27;
%"Q_RES"
"2","(6250,3650)","0","pure_quanta","I56";
;
LOCATION"R363"
$SEC"1"
CDS_SEC"1"
WATTAGE"1/16W"
TOLERANCE"1%"
MATERIAL"CHIP"
VALUE"1K"
PACK_TYPE"0402LF"
CDS_LIB"pure_quanta"
PART_NUMBER"CS21002FB06";
"A"
$PN"1"60;
"B"
$PN"2"28;
%"Q_RES"
"2","(6550,3650)","0","pure_quanta","I57";
;
LOCATION"R367"
$SEC"1"
CDS_SEC"1"
VALUE"1K"
WATTAGE"1/16W"
MATERIAL"CHIP"
TOLERANCE"1%"
PACK_TYPE"0402LF"
CDS_LIB"pure_quanta"
PART_NUMBER"CS21002FB06";
"A"
$PN"1"61;
"B"
$PN"2"39;
%"Q_RES"
"2","(6850,2725)","0","pure_quanta","I58";
;
LOCATION"R369"
$SEC"1"
CDS_SEC"1"
PACK_TYPE"0402LF"
MATERIAL"CHIP"
WATTAGE"1/16W"
VALUE"1K"
TOLERANCE"1%"
CDS_LIB"pure_quanta"
PART_NUMBER"CS21002FB06";
"A"
$PN"1"62;
"B"
$PN"2"38;
%"VCC_CORE"
"1","(6225,3050)","0","pure_quanta_power","I59";
;
HDL_POWER"PVDD11_S3_P1"
CDS_LIB"pure_quanta_power";
"A"59;
%"Q_RES"
"1","(1725,1100)","0","pure_quanta","I6";
;
LOCATION"R148"
$SEC"1"
CDS_SEC"1"
VALUE"0"
MATERIAL"EMPTY"
CDS_LIB"pure_quanta"
WATTAGE"1/16W"
TOLERANCE"5%"
PACK_TYPE"0402LF"
PART_NUMBER"CS00002JB13";
"B"
$PN"2"32;
"A"
$PN"1"24;
%"Q_RES"
"2","(6875,3650)","0","pure_quanta","I60";
;
LOCATION"R370"
$SEC"1"
CDS_SEC"1"
PACK_TYPE"0402LF"
WATTAGE"1/16W"
TOLERANCE"1%"
VALUE"1K"
MATERIAL"CHIP"
CDS_LIB"pure_quanta"
PART_NUMBER"CS21002FB06";
"A"
$PN"1"61;
"B"
$PN"2"40;
%"VCC_CORE"
"1","(6250,3975)","0","pure_quanta_power","I65";
;
HDL_POWER"PVDD11_S3_P0"
CDS_LIB"pure_quanta_power";
"A"60;
%"PI3CSW12ZUAEX"
"1","(1625,1925)","2","pure_quanta","I67";
;
LOCATION"U6"
SEC"1"
MATERIAL"IC"
PART_TYPE"SMLF"
VALUE"PI3CSW12ZUAEX"
NEEDS_NO_SIZE"TRUE"
SEC_TYPE""
CDS_LMAN_SYM_OUTLINE"-150,200,150,-200"
CDS_LIB"pure_quanta"
PART_NUMBER"AL3CSW12000";
"D+"
$PN"8"23;
"GND"
$PN"5"1;
"1D-"
$PN"2"21;
"VDD"
$PN"10"57;
"S"
$PN"9"36;
"OE# \B"
$PN"6"33;
"D-"
$PN"7"24;
"2D-"
$PN"4"32;
"2D+"
$PN"3"31;
"1D+"
$PN"1"22;
%"Q_CAP"
"1","(750,2350)","0","pure_quanta","I69";
;
LOCATION"C25"
$SEC"1"
CDS_SEC"1"
TOLERANCE"10%"
VOLTAGE"25V"
PACK_TYPE"0402"
VALUE"0.1UF"
MATERIAL"X7R"
CDS_LIB"pure_quanta"
PART_NUMBER"CH4104K1B00";
"B"
$PN"2"6;
"A"
$PN"1"57;
%"UNIVERSAL_GND"
"1","(750,2150)","0","pure_quanta_power","I70";
;
CDS_LIB"pure_quanta_power"
HDL_POWER"GND";
"A"6;
%"Q_RES"
"1","(3150,3825)","0","pure_quanta","I73";
;
LOCATION"R1158"
$SEC"1"
CDS_SEC"1"
MATERIAL"EMPTY"
VALUE"33"
PACK_TYPE"0402LF"
TOLERANCE"5%"
WATTAGE"1/16W"
CDS_LIB"pure_quanta"
PART_NUMBER"CS03302JB10";
"B"
$PN"2"42;
"A"
$PN"1"46;
%"Q_RES"
"1","(3150,3875)","0","pure_quanta","I74";
;
LOCATION"R1157"
$SEC"1"
CDS_SEC"1"
MATERIAL"EMPTY"
VALUE"33"
CDS_LIB"pure_quanta"
PACK_TYPE"0402LF"
TOLERANCE"5%"
WATTAGE"1/16W"
PART_NUMBER"CS03302JB10";
"B"
$PN"2"43;
"A"
$PN"1"45;
%"Q_RES"
"1","(3175,1875)","0","pure_quanta","I75";
;
LOCATION"R1160"
$SEC"1"
CDS_SEC"1"
VALUE"0"
CDS_LIB"pure_quanta"
PACK_TYPE"0402LF"
TOLERANCE"5%"
MATERIAL"CHIP"
WATTAGE"1/16W"
PART_NUMBER"CS00002JB13";
"B"
$PN"2"35;
"A"
$PN"1"21;
%"Q_RES"
"1","(3175,1925)","0","pure_quanta","I76";
;
LOCATION"R1159"
$SEC"1"
CDS_SEC"1"
VALUE"0"
CDS_LIB"pure_quanta"
WATTAGE"1/16W"
MATERIAL"CHIP"
TOLERANCE"5%"
PACK_TYPE"0402LF"
PART_NUMBER"CS00002JB13";
"B"
$PN"2"34;
"A"
$PN"1"22;
%"P1V0"
"1","(6875,3975)","0","pure_quanta_power","I81";
;
HDL_POWER"PVDD18_S5_P0"
CDS_LIB"pure_quanta_power";
"A"61;
%"P1V0"
"1","(6850,3050)","0","pure_quanta_power","I82";
;
HDL_POWER"PVDD18_S5_P1"
CDS_LIB"pure_quanta_power";
"A"62;
%"UNIVERSAL_GND"
"1","(3825,5125)","0","pure_quanta_power","I86";
;
CDS_LIB"pure_quanta_power"
HDL_POWER"GND";
"A"7;
%"P1V0"
"1","(4150,6200)","0","pure_quanta_power","I87";
;
HDL_POWER"P3V3_AUX"
CDS_LIB"pure_quanta_power";
"A"56;
%"UNIVERSAL_GND"
"1","(3750,5700)","0","pure_quanta_power","I88";
;
CDS_LIB"pure_quanta_power"
HDL_POWER"GND";
"A"8;
%"Q_CAP"
"1","(3750,5900)","0","pure_quanta","I89";
;
LOCATION"C11"
$SEC"1"
CDS_SEC"1"
VALUE"0.1UF"
VOLTAGE"25V"
PACK_TYPE"0402"
MATERIAL"X7R"
TOLERANCE"10%"
CDS_LIB"pure_quanta"
PART_NUMBER"CH4104K1B00";
"B"
$PN"2"8;
"A"
$PN"1"56;
%"Q_RES"
"1","(5825,5450)","0","pure_quanta","I91";
;
LOCATION"R327"
$SEC"1"
CDS_SEC"1"
MATERIAL"CHIP"
VALUE"0"
PACK_TYPE"0402LF"
CDS_LIB"pure_quanta"
TOLERANCE"5%"
WATTAGE"1/16W"
PART_NUMBER"CS00002JB13";
"B"
$PN"2"49;
"A"
$PN"1"50;
%"Q_RES"
"1","(5825,5400)","0","pure_quanta","I92";
;
LOCATION"R328"
$SEC"1"
CDS_SEC"1"
MATERIAL"CHIP"
PACK_TYPE"0402LF"
VALUE"0"
TOLERANCE"5%"
WATTAGE"1/16W"
CDS_LIB"pure_quanta"
PART_NUMBER"CS00002JB13";
"B"
$PN"2"51;
"A"
$PN"1"9;
%"Q_RES"
"1","(5825,5350)","0","pure_quanta","I93";
;
LOCATION"R337"
$SEC"1"
CDS_SEC"1"
MATERIAL"CHIP"
PACK_TYPE"0402LF"
VALUE"0"
WATTAGE"1/16W"
TOLERANCE"5%"
CDS_LIB"pure_quanta"
PART_NUMBER"CS00002JB13";
"B"
$PN"2"52;
"A"
$PN"1"53;
%"Q_RES"
"1","(5825,5300)","0","pure_quanta","I94";
;
LOCATION"R338"
$SEC"1"
CDS_SEC"1"
MATERIAL"CHIP"
VALUE"0"
PACK_TYPE"0402LF"
CDS_LIB"pure_quanta"
WATTAGE"1/16W"
TOLERANCE"5%"
PART_NUMBER"CS00002JB13";
"B"
$PN"2"54;
"A"
$PN"1"55;
%"Q_RES"
"1","(3025,5550)","0","pure_quanta","I99";
;
LOCATION"R325"
$SEC"1"
CDS_SEC"1"
PACK_TYPE"0402LF"
VALUE"0"
MATERIAL"CHIP"
WATTAGE"1/16W"
TOLERANCE"5%"
CDS_LIB"pure_quanta"
PART_NUMBER"CS00002JB13";
"B"
$PN"2"13;
"A"
$PN"1"48;
END.
